# T6G (Grand Teton) — schematic netlist excerpt (pin names and nets, part order shuffled) for the footprints in the layout excerpt that follows; sources: Cadence DE-HDL packaged netlist, KiCad conversion of 04192023_DAF0TMB3IC0_F0TG_MB_C_brd_V02_OCP.brd

PR137  Q_RES  0 5% CHIP  pkg 0402LF  page 208 : A = PVDD11_S3_P0_VOS1 ; B = PVDD11_S3_P0
R3241  Q_RES  2.2K 5% EMPTY  pkg 0402LF  page 151 : A = SMB_OCP_SFF_3V3AUX_SDA ; B = P3V3_AUX
PC7000  Q_CAP  22UF 16V 20% X6S  pkg C0805  page 205 : A = SW_P12V_AUX_PVDDIO_P0_FLT ; B = GND

(kicad_pcb
	(version 20260206)
	(generator "pcbnew")
	(generator_version "10.0")
	(general
		(thickness 1.6)
		(legacy_teardrops no)
	)
	(paper "A4")
	(title_block
		(title "04192023_DAF0TMB3IC0_F0TG_MB_C_brd_V02_OCP.brd")
		(comment 1 "Grand Teton / footprints 7048-7050 of 8354")
	)
	(layers
		(0 "F.Cu" signal "TOP")
		(4 "In1.Cu" signal "GND")
		(6 "In2.Cu" signal "IN1")
		(8 "In3.Cu" signal "GND1")
		(10 "In4.Cu" signal "IN2")
		(12 "In5.Cu" signal "GND2")
		(14 "In6.Cu" signal "IN3")
		(16 "In7.Cu" signal "GND3")
		(18 "In8.Cu" signal "VCC")
		(20 "In9.Cu" signal "VCC1")
		(22 "In10.Cu" signal "GND4")
		(24 "In11.Cu" signal "IN4")
		(26 "In12.Cu" signal "GND5")
		(28 "In13.Cu" signal "IN5")
		(30 "In14.Cu" signal "GND6")
		(32 "In15.Cu" signal "IN6")
		(34 "In16.Cu" signal "GND7")
		(2 "B.Cu" signal "BOTTOM")
		(9 "F.Adhes" user "F.Adhesive")
		(11 "B.Adhes" user "B.Adhesive")
		(13 "F.Paste" user "Package Geometry/Pastemask Top")
		(15 "B.Paste" user "Package Geometry/Pastemask Bottom")
		(5 "F.SilkS" user "Ref Des/Silkscreen Top")
		(7 "B.SilkS" user "Ref Des/Silkscreen Bottom")
		(1 "F.Mask" user "Board Geometry/Soldermask Top")
		(3 "B.Mask" user "Board Geometry/Soldermask Bottom")
		(17 "Dwgs.User" user "User.Drawings")
		(19 "Cmts.User" user "User.Comments")
		(21 "Eco1.User" user "User.Eco1")
		(23 "Eco2.User" user "User.Eco2")
		(25 "Edge.Cuts" user "Board Geometry/Outline")
		(27 "Margin" user)
		(31 "F.CrtYd" user "Package Geometry/Place Bound Top")
		(29 "B.CrtYd" user "Package Geometry/Place Bound Bottom")
		(35 "F.Fab" user "Ref Des/Assembly Top")
		(33 "B.Fab" user "Ref Des/Assembly Bottom")
	)
	(footprint ""
		(layer "B.Cu")
		(at 182.541164 -23.655782 -90)
		(property "Reference" "R3241"
			(at 0 0 90)
			(layer "B.SilkS")
			(hide yes)
			(effects
				(font
					(size 1.27 1.27)
				)
				(justify mirror)
			)
		)
		(property "Value" ""
			(at 0 0 90)
			(layer "B.Fab")
			(effects
				(font
					(size 1.27 1.27)
				)
				(justify mirror)
			)
		)
		(duplicate_pad_numbers_are_jumpers no)
		(fp_line
			(start -0.7874 0.4064)
			(end 0.7874 0.4064)
			(stroke
				(width 0.1524)
				(type default)
			)
			(layer "B.SilkS")
		)
		(fp_line
			(start 0.7874 0.4064)
			(end 0.7874 -0.4064)
			(stroke
				(width 0.1524)
				(type default)
			)
			(layer "B.SilkS")
		)
		(fp_line
			(start -0.7874 -0.4064)
			(end -0.7874 0.4064)
			(stroke
				(width 0.1524)
				(type default)
			)
			(layer "B.SilkS")
		)
		(fp_line
			(start 0.7874 -0.4064)
			(end -0.7874 -0.4064)
			(stroke
				(width 0.1524)
				(type default)
			)
			(layer "B.SilkS")
		)
		(fp_line
			(start -0.67945 0.3048)
			(end -0.120396 0.3048)
			(stroke
				(width 0.1)
				(type default)
			)
			(layer "B.Fab")
		)
		(fp_line
			(start -0.120396 0.3048)
			(end -0.120396 0.2794)
			(stroke
				(width 0.1)
				(type default)
			)
			(layer "B.Fab")
		)
		(fp_line
			(start 0.12065 0.3048)
			(end 0.67945 0.3048)
			(stroke
				(width 0.1)
				(type default)
			)
			(layer "B.Fab")
		)
		(fp_line
			(start 0.67945 0.3048)
			(end 0.67945 -0.305054)
			(stroke
				(width 0.1)
				(type default)
			)
			(layer "B.Fab")
		)
		(fp_line
			(start -0.120396 0.2794)
			(end 0.12065 0.2794)
			(stroke
				(width 0.1)
				(type default)
			)
			(layer "B.Fab")
		)
		(fp_line
			(start 0.12065 0.2794)
			(end 0.12065 0.3048)
			(stroke
				(width 0.1)
				(type default)
			)
			(layer "B.Fab")
		)
		(fp_line
			(start -0.12065 -0.2794)
			(end -0.12065 -0.3048)
			(stroke
				(width 0.1)
				(type default)
			)
			(layer "B.Fab")
		)
		(fp_line
			(start 0.12065 -0.2794)
			(end -0.12065 -0.2794)
			(stroke
				(width 0.1)
				(type default)
			)
			(layer "B.Fab")
		)
		(fp_line
			(start -0.67945 -0.3048)
			(end -0.67945 0.3048)
			(stroke
				(width 0.1)
				(type default)
			)
			(layer "B.Fab")
		)
		(fp_line
			(start -0.12065 -0.3048)
			(end -0.67945 -0.3048)
			(stroke
				(width 0.1)
				(type default)
			)
			(layer "B.Fab")
		)
		(fp_line
			(start 0.12065 -0.305054)
			(end 0.12065 -0.2794)
			(stroke
				(width 0.1)
				(type default)
			)
			(layer "B.Fab")
		)
		(fp_line
			(start 0.67945 -0.305054)
			(end 0.12065 -0.305054)
			(stroke
				(width 0.1)
				(type default)
			)
			(layer "B.Fab")
		)
		(pad "1" smd circle
			(at 0.40005 0 90)
			(size 0 0)
			(layers "B.Cu" "B.Mask" "B.Paste")
			(net "SMB_OCP_SFF_3V3AUX_SDA")
		)
		(pad "2" smd circle
			(at -0.40005 0 90)
			(size 0 0)
			(layers "B.Cu" "B.Mask" "B.Paste")
			(net "P3V3_AUX")
		)
	)
	(footprint ""
		(layer "B.Cu")
		(at 290.68268 -352.95332 90)
		(property "Reference" "PC7000"
			(at 0 0 90)
			(layer "B.SilkS")
			(hide yes)
			(effects
				(font
					(size 1.27 1.27)
				)
				(justify mirror)
			)
		)
		(property "Value" ""
			(at 0 0 90)
			(layer "B.Fab")
			(effects
				(font
					(size 1.27 1.27)
				)
				(justify mirror)
			)
		)
		(duplicate_pad_numbers_are_jumpers no)
		(fp_line
			(start 1.524 -0.762)
			(end -1.524 -0.762)
			(stroke
				(width 0.1524)
				(type default)
			)
			(layer "B.SilkS")
		)
		(fp_line
			(start -1.524 -0.762)
			(end -1.524 0.762)
			(stroke
				(width 0.1524)
				(type default)
			)
			(layer "B.SilkS")
		)
		(fp_line
			(start 1.524 0.762)
			(end 1.524 -0.762)
			(stroke
				(width 0.1524)
				(type default)
			)
			(layer "B.SilkS")
		)
		(fp_line
			(start -1.524 0.762)
			(end 1.524 0.762)
			(stroke
				(width 0.1524)
				(type default)
			)
			(layer "B.SilkS")
		)
		(fp_line
			(start 1.1049 -0.724916)
			(end 1.1049 0.724916)
			(stroke
				(width 0.1)
				(type default)
			)
			(layer "B.Fab")
		)
		(fp_line
			(start -1.1049 -0.724916)
			(end 1.1049 -0.724916)
			(stroke
				(width 0.1)
				(type default)
			)
			(layer "B.Fab")
		)
		(fp_line
			(start 1.1049 0.724916)
			(end -1.1049 0.724916)
			(stroke
				(width 0.1)
				(type default)
			)
			(layer "B.Fab")
		)
		(fp_line
			(start -1.1049 0.724916)
			(end -1.1049 -0.724916)
			(stroke
				(width 0.1)
				(type default)
			)
			(layer "B.Fab")
		)
		(pad "1" smd rect
			(at 0.889 0 90)
			(size 1.016 1.27)
			(layers "B.Cu" "B.Mask" "B.Paste")
			(net "SW_P12V_AUX_PVDDIO_P0_FLT")
		)
		(pad "2" smd rect
			(at -0.889 0 90)
			(size 1.016 1.27)
			(layers "B.Cu" "B.Mask" "B.Paste")
			(net "GND")
		)
	)
	(footprint ""
		(layer "B.Cu")
		(at 419.98265 -353.78009 -90)
		(property "Reference" "PR137"
			(at 0 0 90)
			(layer "B.SilkS")
			(hide yes)
			(effects
				(font
					(size 1.27 1.27)
				)
				(justify mirror)
			)
		)
		(property "Value" ""
			(at 0 0 90)
			(layer "B.Fab")
			(effects
				(font
					(size 1.27 1.27)
				)
				(justify mirror)
			)
		)
		(duplicate_pad_numbers_are_jumpers no)
		(fp_line
			(start -0.7874 0.4064)
			(end 0.7874 0.4064)
			(stroke
				(width 0.1524)
				(type default)
			)
			(layer "B.SilkS")
		)
		(fp_line
			(start 0.7874 0.4064)
			(end 0.7874 -0.4064)
			(stroke
				(width 0.1524)
				(type default)
			)
			(layer "B.SilkS")
		)
		(fp_line
			(start -0.7874 -0.4064)
			(end -0.7874 0.4064)
			(stroke
				(width 0.1524)
				(type default)
			)
			(layer "B.SilkS")
		)
		(fp_line
			(start 0.7874 -0.4064)
			(end -0.7874 -0.4064)
			(stroke
				(width 0.1524)
				(type default)
			)
			(layer "B.SilkS")
		)
		(fp_line
			(start -0.67945 0.3048)
			(end -0.120396 0.3048)
			(stroke
				(width 0.1)
				(type default)
			)
			(layer "B.Fab")
		)
		(fp_line
			(start -0.120396 0.3048)
			(end -0.120396 0.2794)
			(stroke
				(width 0.1)
				(type default)
			)
			(layer "B.Fab")
		)
		(fp_line
			(start 0.12065 0.3048)
			(end 0.67945 0.3048)
			(stroke
				(width 0.1)
				(type default)
			)
			(layer "B.Fab")
		)
		(fp_line
			(start 0.67945 0.3048)
			(end 0.67945 -0.305054)
			(stroke
				(width 0.1)
				(type default)
			)
			(layer "B.Fab")
		)
		(fp_line
			(start -0.120396 0.2794)
			(end 0.12065 0.2794)
			(stroke
				(width 0.1)
				(type default)
			)
			(layer "B.Fab")
		)
		(fp_line
			(start 0.12065 0.2794)
			(end 0.12065 0.3048)
			(stroke
				(width 0.1)
				(type default)
			)
			(layer "B.Fab")
		)
		(fp_line
			(start -0.12065 -0.2794)
			(end -0.12065 -0.3048)
			(stroke
				(width 0.1)
				(type default)
			)
			(layer "B.Fab")
		)
		(fp_line
			(start 0.12065 -0.2794)
			(end -0.12065 -0.2794)
			(stroke
				(width 0.1)
				(type default)
			)
			(layer "B.Fab")
		)
		(fp_line
			(start -0.67945 -0.3048)
			(end -0.67945 0.3048)
			(stroke
				(width 0.1)
				(type default)
			)
			(layer "B.Fab")
		)
		(fp_line
			(start -0.12065 -0.3048)
			(end -0.67945 -0.3048)
			(stroke
				(width 0.1)
				(type default)
			)
			(layer "B.Fab")
		)
		(fp_line
			(start 0.12065 -0.305054)
			(end 0.12065 -0.2794)
			(stroke
				(width 0.1)
				(type default)
			)
			(layer "B.Fab")
		)
		(fp_line
			(start 0.67945 -0.305054)
			(end 0.12065 -0.305054)
			(stroke
				(width 0.1)
				(type default)
			)
			(layer "B.Fab")
		)
		(pad "1" smd circle
			(at 0.40005 0 90)
			(size 0 0)
			(layers "B.Cu" "B.Mask" "B.Paste")
			(net "PVDD11_S3_P0_VOS1")
		)
		(pad "2" smd circle
			(at -0.40005 0 90)
			(size 0 0)
			(layers "B.Cu" "B.Mask" "B.Paste")
			(net "PVDD11_S3_P0")
		)
	)
)
